(kicad_pcb
	(version 20260206)
	(generator "pcbnew")
	(generator_version "10.0")
	(general
		(thickness 1.6)
		(legacy_teardrops no)
	)
	(paper "A4")
	(title_block
		(title "Bryce Canyon_IOM_M2_16342-2_OCP.brd")
		(comment 1 "Bryce Canyon / footprints 157-162 of 1146")
	)
	(layers
		(0 "F.Cu" signal "TOP")
		(4 "In1.Cu" signal "L2GND")
		(6 "In2.Cu" signal "L3")
		(8 "In3.Cu" signal "L4VCC")
		(10 "In4.Cu" signal "L5VCC")
		(12 "In5.Cu" signal "L6")
		(14 "In6.Cu" signal "L7GND")
		(2 "B.Cu" signal "BOTTOM")
		(9 "F.Adhes" user "F.Adhesive")
		(11 "B.Adhes" user "B.Adhesive")
		(13 "F.Paste" user "Package Geometry/Pastemask Top")
		(15 "B.Paste" user "Package Geometry/Pastemask Bottom")
		(5 "F.SilkS" user "Ref Des/Silkscreen Top")
		(7 "B.SilkS" user "Ref Des/Silkscreen Bottom")
		(1 "F.Mask" user "Board Geometry/Soldermask Top")
		(3 "B.Mask" user "Board Geometry/Soldermask Bottom")
		(17 "Dwgs.User" user "User.Drawings")
		(19 "Cmts.User" user "User.Comments")
		(21 "Eco1.User" user "User.Eco1")
		(23 "Eco2.User" user "User.Eco2")
		(25 "Edge.Cuts" user "Board Geometry/Outline")
		(27 "Margin" user)
		(31 "F.CrtYd" user "Package Geometry/Place Bound Top")
		(29 "B.CrtYd" user "Package Geometry/Place Bound Bottom")
		(35 "F.Fab" user "Ref Des/Assembly Top")
		(33 "B.Fab" user "Ref Des/Assembly Bottom")
	)
	(footprint ""
		(layer "F.Cu")
		(at 72.4662 -132.7912 90)
		(property "Reference" "R99"
			(at 0 0 90)
			(layer "F.SilkS")
			(hide yes)
			(effects
				(font
					(size 1.27 1.27)
				)
			)
		)
		(property "Value" "0R2J-2-GP"
			(at 0.064008 -3.993896 90)
			(unlocked yes)
			(layer "F.Fab")
			(hide yes)
			(effects
				(font
					(size 1.016 1.016)
					(thickness 0.1524)
				)
			)
		)
		(property "Device Type" "R402H16"
			(at 0.064008 -5.517896 90)
			(unlocked yes)
			(layer "F.Fab")
			(hide yes)
			(effects
				(font
					(size 1.016 1.016)
					(thickness 0.1524)
				)
			)
		)
		(duplicate_pad_numbers_are_jumpers no)
		(fp_line
			(start 0.508 -0.9398)
			(end -0.508 -0.9398)
			(stroke
				(width 0.1524)
				(type default)
			)
			(layer "F.SilkS")
		)
		(fp_line
			(start -0.508 -0.9398)
			(end -0.508 0.9398)
			(stroke
				(width 0.1524)
				(type default)
			)
			(layer "F.SilkS")
		)
		(fp_rect
			(start -0.508 0.9398)
			(end 0.508 -0.9398)
			(stroke
				(width 0)
				(type default)
			)
			(fill no)
			(layer "F.CrtYd")
		)
		(fp_rect
			(start -0.508 0.9398)
			(end 0.508 -0.9398)
			(stroke
				(width 0)
				(type default)
			)
			(fill no)
			(layer "F.Fab")
		)
		(pad "1" smd custom
			(at 0 -0.4445 90)
			(size 0.1397 0.1397)
			(layers "F.Cu" "F.Mask" "F.Paste")
			(net "P3V3_STBY")
			(options
				(clearance outline)
				(anchor circle)
			)
			(primitives
				(gr_poly
					(pts
						(arc
							(start -0.1778 -0.2794)
							(mid -0.249642 -0.249642)
							(end -0.2794 -0.1778)
						)
						(arc
							(start -0.2794 0.1778)
							(mid -0.249642 0.249642)
							(end -0.1778 0.2794)
						)
						(arc
							(start 0.1778 0.2794)
							(mid 0.249642 0.249642)
							(end 0.2794 0.1778)
						)
						(arc
							(start 0.2794 -0.1778)
							(mid 0.249642 -0.249642)
							(end 0.1778 -0.2794)
						)
					)
					(width 0)
					(fill yes)
				)
			)
		)
		(pad "2" smd custom
			(at 0 0.4445 90)
			(size 0.1397 0.1397)
			(layers "F.Cu" "F.Mask" "F.Paste")
			(net "D_FLIP_PRE#")
			(options
				(clearance outline)
				(anchor circle)
			)
			(primitives
				(gr_poly
					(pts
						(arc
							(start -0.1778 -0.2794)
							(mid -0.249642 -0.249642)
							(end -0.2794 -0.1778)
						)
						(arc
							(start -0.2794 0.1778)
							(mid -0.249642 0.249642)
							(end -0.1778 0.2794)
						)
						(arc
							(start 0.1778 0.2794)
							(mid 0.249642 0.249642)
							(end 0.2794 0.1778)
						)
						(arc
							(start 0.2794 -0.1778)
							(mid 0.249642 -0.249642)
							(end 0.1778 -0.2794)
						)
					)
					(width 0)
					(fill yes)
				)
			)
		)
	)
	(footprint ""
		(layer "F.Cu")
		(at 196.2404 -6.985)
		(property "Reference" "Q27"
			(at 0 0 0)
			(layer "F.SilkS")
			(hide yes)
			(effects
				(font
					(size 1.27 1.27)
				)
			)
		)
		(property "Value" "SSM6P39TU-GP"
			(at 0.0508 -11.5824 0)
			(unlocked yes)
			(layer "F.Fab")
			(hide yes)
			(effects
				(font
					(size 1.016 1.016)
					(thickness 0.1524)
				)
			)
		)
		(property "Device Type" "UMT6H30"
			(at 0.0508 -13.1572 0)
			(unlocked yes)
			(layer "F.Fab")
			(hide yes)
			(effects
				(font
					(size 1.016 1.016)
					(thickness 0.1524)
				)
			)
		)
		(duplicate_pad_numbers_are_jumpers no)
		(fp_line
			(start -1.27 -0.36449)
			(end -1.27 0.36449)
			(stroke
				(width 0.1524)
				(type default)
			)
			(layer "F.SilkS")
		)
		(fp_line
			(start -1.27 -0.36449)
			(end 1.524 -0.36449)
			(stroke
				(width 0.1524)
				(type default)
			)
			(layer "F.SilkS")
		)
		(fp_line
			(start 1.09347 0)
			(end 1.45796 0.36449)
			(stroke
				(width 0.1524)
				(type default)
			)
			(layer "F.SilkS")
		)
		(fp_line
			(start 1.45796 -0.36449)
			(end 1.09347 0)
			(stroke
				(width 0.1524)
				(type default)
			)
			(layer "F.SilkS")
		)
		(fp_line
			(start 1.524 -0.36449)
			(end 1.45796 -0.36449)
			(stroke
				(width 0.1524)
				(type default)
			)
			(layer "F.SilkS")
		)
		(fp_line
			(start 1.524 -0.36449)
			(end 1.524 -1.82245)
			(stroke
				(width 0.508)
				(type default)
			)
			(layer "F.SilkS")
		)
		(fp_line
			(start 1.524 -0.36449)
			(end 1.524 0.36449)
			(stroke
				(width 0.1524)
				(type default)
			)
			(layer "F.SilkS")
		)
		(fp_line
			(start 1.524 0.36449)
			(end -1.27 0.36449)
			(stroke
				(width 0.1524)
				(type default)
			)
			(layer "F.SilkS")
		)
		(fp_poly
			(pts
				(xy -0.65024 0.36449) (xy -0.65024 -0.36449) (xy 0.65024 -0.36449) (xy 0.65024 0.36449)
			)
			(stroke
				(width 0)
				(type default)
			)
			(fill yes)
			(layer "F.SilkS")
		)
		(fp_poly
			(pts
				(xy 1.016 -1.0668) (xy 1.016 1.0668) (xy -1.016 1.0668) (xy -1.016 -1.0668)
			)
			(stroke
				(width 0)
				(type default)
			)
			(fill no)
			(layer "F.CrtYd")
		)
		(fp_poly
			(pts
				(xy -1.524 1.905) (xy 1.524 1.905) (xy 1.524 -1.06426) (xy 1.016 -1.06426) (xy 1.016 1.0668) (xy -1.016 1.0668)
				(xy -1.016 -1.0668) (xy 1.524 -1.0668) (xy 1.524 -1.905) (xy -1.524 -1.905)
			)
			(stroke
				(width 0)
				(type default)
			)
			(fill no)
			(layer "F.CrtYd")
		)
		(fp_poly
			(pts
				(xy -1.524 -1.905) (xy -1.524 1.905) (xy 1.524 1.905) (xy 1.524 -1.905)
			)
			(stroke
				(width 0)
				(type default)
			)
			(fill no)
			(layer "F.Fab")
		)
		(pad "1" smd rect
			(at 0.65024 -1.02489)
			(size 0.4064 0.8128)
			(layers "F.Cu" "F.Mask" "F.Paste")
			(net "P3V3_STBY")
		)
		(pad "2" smd rect
			(at 0 -1.02489)
			(size 0.4064 0.8128)
			(layers "F.Cu" "F.Mask" "F.Paste")
			(net "BMC_ML_PWR_YELLOW_LED_R")
		)
		(pad "3" smd rect
			(at -0.65024 -1.02489)
			(size 0.4064 0.8128)
			(layers "F.Cu" "F.Mask" "F.Paste")
			(net "ML_PWR_BLUE_LED")
		)
		(pad "4" smd rect
			(at -0.65024 1.02489)
			(size 0.4064 0.8128)
			(layers "F.Cu" "F.Mask" "F.Paste")
			(net "P5V_STBY")
		)
		(pad "5" smd rect
			(at 0 1.02489)
			(size 0.4064 0.8128)
			(layers "F.Cu" "F.Mask" "F.Paste")
			(net "BMC_ML_PWR_BLUE_LED_L")
		)
		(pad "6" smd rect
			(at 0.65024 1.02489)
			(size 0.4064 0.8128)
			(layers "F.Cu" "F.Mask" "F.Paste")
			(net "ML_PWR_YELLOW_LED")
		)
	)
	(footprint ""
		(layer "F.Cu")
		(at 36.28771 -121.3612 90)
		(property "Reference" "U11"
			(at 0 0 90)
			(layer "F.SilkS")
			(hide yes)
			(effects
				(font
					(size 1.27 1.27)
				)
			)
		)
		(property "Value" "W25Q256FVFIQ-GP"
			(at -6.7945 -2.2098 90)
			(unlocked yes)
			(layer "F.Fab")
			(hide yes)
			(effects
				(font
					(size 1.016 1.016)
					(thickness 0.1524)
				)
			)
		)
		(property "Device Type" "SOIC16-6H104"
			(at -6.7945 -3.7338 90)
			(unlocked yes)
			(layer "F.Fab")
			(hide yes)
			(effects
				(font
					(size 1.016 1.016)
					(thickness 0.1524)
				)
			)
		)
		(duplicate_pad_numbers_are_jumpers no)
		(fp_line
			(start 4.7498 -3.2258)
			(end 4.7498 3.2258)
			(stroke
				(width 0.1524)
				(type default)
			)
			(layer "F.SilkS")
		)
		(fp_line
			(start -5.588 -3.2258)
			(end 4.7498 -3.2258)
			(stroke
				(width 0.1524)
				(type default)
			)
			(layer "F.SilkS")
		)
		(fp_line
			(start -5.588 -0.50038)
			(end -5.08762 0)
			(stroke
				(width 0.1524)
				(type default)
			)
			(layer "F.SilkS")
		)
		(fp_line
			(start -5.08762 0)
			(end -5.588 0.50038)
			(stroke
				(width 0.1524)
				(type default)
			)
			(layer "F.SilkS")
		)
		(fp_line
			(start 4.7498 3.2258)
			(end -5.588 3.2258)
			(stroke
				(width 0.1524)
				(type default)
			)
			(layer "F.SilkS")
		)
		(fp_line
			(start -5.4102 3.2258)
			(end -5.4102 5.7912)
			(stroke
				(width 0.508)
				(type default)
			)
			(layer "F.SilkS")
		)
		(fp_line
			(start -5.588 3.2258)
			(end -5.588 -3.2258)
			(stroke
				(width 0.1524)
				(type default)
			)
			(layer "F.SilkS")
		)
		(fp_poly
			(pts
				(xy -4.764786 -3.2258) (xy 4.7625 -3.2258) (xy 4.7625 3.2258) (xy -4.764786 3.2258)
			)
			(stroke
				(width 0)
				(type default)
			)
			(fill yes)
			(layer "F.SilkS")
		)
		(fp_rect
			(start -5.1435 5.1562)
			(end 5.1435 -5.1562)
			(stroke
				(width 0)
				(type default)
			)
			(fill no)
			(layer "F.CrtYd")
		)
		(fp_poly
			(pts
				(xy -5.6642 6.0452) (xy -5.6642 -6.0452) (xy 5.6642 -6.0452) (xy 5.6642 -1.7653) (xy 5.1435 -1.7653)
				(xy 5.1435 -5.1562) (xy -5.1435 -5.1562) (xy -5.1435 5.1562) (xy 5.1435 5.1562) (xy 5.1435 -1.7526)
				(xy 5.6642 -1.7526) (xy 5.6642 6.0452)
			)
			(stroke
				(width 0)
				(type default)
			)
			(fill no)
			(layer "F.CrtYd")
		)
		(fp_rect
			(start -5.6642 6.0452)
			(end 5.6642 -6.0452)
			(stroke
				(width 0)
				(type default)
			)
			(fill no)
			(layer "F.Fab")
		)
		(pad "1" smd rect
			(at -4.445 4.71805 90)
			(size 0.635 1.651)
			(layers "F.Cu" "F.Mask" "F.Paste")
			(net "FLA0_SPI_HOLD_N")
		)
		(pad "2" smd rect
			(at -3.175 4.71805 90)
			(size 0.635 1.651)
			(layers "F.Cu" "F.Mask" "F.Paste")
			(net "P3V3_STBY")
		)
		(pad "3" smd rect
			(at -1.905 4.71805 90)
			(size 0.635 1.651)
			(layers "F.Cu" "F.Mask" "F.Paste")
			(net "FLA0_SPI_RST")
		)
		(pad "4" smd rect
			(at -0.635 4.71805 90)
			(size 0.635 1.651)
			(layers "F.Cu" "F.Mask" "F.Paste")
			(net "Net_570")
		)
		(pad "5" smd rect
			(at 0.635 4.71805 90)
			(size 0.635 1.651)
			(layers "F.Cu" "F.Mask" "F.Paste")
			(net "Net_571")
		)
		(pad "6" smd rect
			(at 1.905 4.71805 90)
			(size 0.635 1.651)
			(layers "F.Cu" "F.Mask" "F.Paste")
			(net "Net_572")
		)
		(pad "7" smd rect
			(at 3.175 4.71805 90)
			(size 0.635 1.651)
			(layers "F.Cu" "F.Mask" "F.Paste")
			(net "FLA_CS_0_R")
		)
		(pad "8" smd rect
			(at 4.445 4.71805 90)
			(size 0.635 1.651)
			(layers "F.Cu" "F.Mask" "F.Paste")
			(net "BMC_SPI_MISO_TPM")
		)
		(pad "9" smd rect
			(at 4.445 -4.71805 90)
			(size 0.635 1.651)
			(layers "F.Cu" "F.Mask" "F.Paste")
			(net "FLA0_WP_N")
		)
		(pad "10" smd rect
			(at 3.175 -4.71805 90)
			(size 0.635 1.651)
			(layers "F.Cu" "F.Mask" "F.Paste")
			(net "GND")
		)
		(pad "11" smd rect
			(at 1.905 -4.71805 90)
			(size 0.635 1.651)
			(layers "F.Cu" "F.Mask" "F.Paste")
			(net "Net_566")
		)
		(pad "12" smd rect
			(at 0.635 -4.71805 90)
			(size 0.635 1.651)
			(layers "F.Cu" "F.Mask" "F.Paste")
			(net "Net_567")
		)
		(pad "13" smd rect
			(at -0.635 -4.71805 90)
			(size 0.635 1.651)
			(layers "F.Cu" "F.Mask" "F.Paste")
			(net "Net_568")
		)
		(pad "14" smd rect
			(at -1.905 -4.71805 90)
			(size 0.635 1.651)
			(layers "F.Cu" "F.Mask" "F.Paste")
			(net "Net_569")
		)
		(pad "15" smd rect
			(at -3.175 -4.71805 90)
			(size 0.635 1.651)
			(layers "F.Cu" "F.Mask" "F.Paste")
			(net "BMC_SPI_MOSI_R")
		)
		(pad "16" smd rect
			(at -4.445 -4.71805 90)
			(size 0.635 1.651)
			(layers "F.Cu" "F.Mask" "F.Paste")
			(net "BMC_SPI_CLK_R")
		)
	)
	(footprint ""
		(layer "F.Cu")
		(at 65.659 -172.085 180)
		(property "Reference" "R78"
			(at 0 0 180)
			(layer "F.SilkS")
			(hide yes)
			(effects
				(font
					(size 1.27 1.27)
				)
			)
		)
		(property "Value" "10KR2F-2-GP"
			(at 0.064008 -3.993896 180)
			(unlocked yes)
			(layer "F.Fab")
			(hide yes)
			(effects
				(font
					(size 1.016 1.016)
					(thickness 0.1524)
				)
			)
		)
		(property "Device Type" "R402H16"
			(at 0.064008 -5.517896 180)
			(unlocked yes)
			(layer "F.Fab")
			(hide yes)
			(effects
				(font
					(size 1.016 1.016)
					(thickness 0.1524)
				)
			)
		)
		(duplicate_pad_numbers_are_jumpers no)
		(fp_line
			(start 0.508 -0.9398)
			(end -0.508 -0.9398)
			(stroke
				(width 0.1524)
				(type default)
			)
			(layer "F.SilkS")
		)
		(fp_line
			(start -0.508 -0.9398)
			(end -0.508 0.9398)
			(stroke
				(width 0.1524)
				(type default)
			)
			(layer "F.SilkS")
		)
		(fp_rect
			(start -0.508 0.9398)
			(end 0.508 -0.9398)
			(stroke
				(width 0)
				(type default)
			)
			(fill no)
			(layer "F.CrtYd")
		)
		(fp_rect
			(start -0.508 0.9398)
			(end 0.508 -0.9398)
			(stroke
				(width 0)
				(type default)
			)
			(fill no)
			(layer "F.Fab")
		)
		(pad "1" smd custom
			(at 0 -0.4445 180)
			(size 0.1397 0.1397)
			(layers "F.Cu" "F.Mask" "F.Paste")
			(net "P3V3_STBY")
			(options
				(clearance outline)
				(anchor circle)
			)
			(primitives
				(gr_poly
					(pts
						(arc
							(start -0.1778 -0.2794)
							(mid -0.249642 -0.249642)
							(end -0.2794 -0.1778)
						)
						(arc
							(start -0.2794 0.1778)
							(mid -0.249642 0.249642)
							(end -0.1778 0.2794)
						)
						(arc
							(start 0.1778 0.2794)
							(mid 0.249642 0.249642)
							(end 0.2794 0.1778)
						)
						(arc
							(start 0.2794 -0.1778)
							(mid 0.249642 -0.249642)
							(end 0.1778 -0.2794)
						)
					)
					(width 0)
					(fill yes)
				)
			)
		)
		(pad "2" smd custom
			(at 0 0.4445 180)
			(size 0.1397 0.1397)
			(layers "F.Cu" "F.Mask" "F.Paste")
			(net "FM_TPM_PRSNT_N")
			(options
				(clearance outline)
				(anchor circle)
			)
			(primitives
				(gr_poly
					(pts
						(arc
							(start -0.1778 -0.2794)
							(mid -0.249642 -0.249642)
							(end -0.2794 -0.1778)
						)
						(arc
							(start -0.2794 0.1778)
							(mid -0.249642 0.249642)
							(end -0.1778 0.2794)
						)
						(arc
							(start 0.1778 0.2794)
							(mid 0.249642 0.249642)
							(end 0.2794 0.1778)
						)
						(arc
							(start 0.2794 -0.1778)
							(mid 0.249642 -0.249642)
							(end 0.1778 -0.2794)
						)
					)
					(width 0)
					(fill yes)
				)
			)
		)
	)
	(footprint ""
		(layer "F.Cu")
		(at 53.7972 -181.3306)
		(property "Reference" "C174"
			(at 0 0 0)
			(layer "F.SilkS")
			(hide yes)
			(effects
				(font
					(size 1.27 1.27)
				)
			)
		)
		(property "Value" "SC10U6D3V5KX-4GP"
			(at -0.0762 -6.1214 0)
			(unlocked yes)
			(layer "F.Fab")
			(hide yes)
			(effects
				(font
					(size 1.016 1.016)
					(thickness 0.1524)
				)
			)
		)
		(property "Device Type" "C805H58"
			(at -0.0762 -8.1534 0)
			(unlocked yes)
			(layer "F.Fab")
			(hide yes)
			(effects
				(font
					(size 1.016 1.016)
					(thickness 0.1524)
				)
			)
		)
		(duplicate_pad_numbers_are_jumpers no)
		(fp_line
			(start 0.635 0)
			(end -0.635 0)
			(stroke
				(width 0.508)
				(type default)
			)
			(layer "F.SilkS")
		)
		(fp_rect
			(start -0.9652 1.778)
			(end 0.9652 -1.778)
			(stroke
				(width 0)
				(type default)
			)
			(fill no)
			(layer "F.CrtYd")
		)
		(fp_poly
			(pts
				(xy -0.9652 -1.778) (xy 0.9652 -1.778) (xy 0.9652 1.778) (xy -0.9652 1.778)
			)
			(stroke
				(width 0)
				(type default)
			)
			(fill no)
			(layer "F.Fab")
		)
		(pad "1" smd rect
			(at 0 -0.9652)
			(size 1.397 1.143)
			(layers "F.Cu" "F.Mask" "F.Paste")
			(net "P3V3_STBY_OUT")
		)
		(pad "2" smd rect
			(at 0 0.9652)
			(size 1.397 1.143)
			(layers "F.Cu" "F.Mask" "F.Paste")
			(net "GND")
		)
	)
	(footprint ""
		(layer "F.Cu")
		(at 60.2742 -132.223002 -90)
		(property "Reference" "R289"
			(at 0 0 270)
			(layer "F.SilkS")
			(hide yes)
			(effects
				(font
					(size 1.27 1.27)
				)
			)
		)
		(property "Value" "0R2J-2-GP"
			(at 0.064008 -3.993896 270)
			(unlocked yes)
			(layer "F.Fab")
			(hide yes)
			(effects
				(font
					(size 1.016 1.016)
					(thickness 0.1524)
				)
			)
		)
		(property "Device Type" "R402H16"
			(at 0.064008 -5.517896 270)
			(unlocked yes)
			(layer "F.Fab")
			(hide yes)
			(effects
				(font
					(size 1.016 1.016)
					(thickness 0.1524)
				)
			)
		)
		(duplicate_pad_numbers_are_jumpers no)
		(fp_line
			(start -0.508 -0.9398)
			(end -0.508 0.9398)
			(stroke
				(width 0.1524)
				(type default)
			)
			(layer "F.SilkS")
		)
		(fp_line
			(start 0.508 -0.9398)
			(end -0.508 -0.9398)
			(stroke
				(width 0.1524)
				(type default)
			)
			(layer "F.SilkS")
		)
		(fp_rect
			(start -0.508 0.9398)
			(end 0.508 -0.9398)
			(stroke
				(width 0)
				(type default)
			)
			(fill no)
			(layer "F.CrtYd")
		)
		(fp_rect
			(start -0.508 0.9398)
			(end 0.508 -0.9398)
			(stroke
				(width 0)
				(type default)
			)
			(fill no)
			(layer "F.Fab")
		)
		(pad "1" smd custom
			(at 0 -0.4445 270)
			(size 0.1397 0.1397)
			(layers "F.Cu" "F.Mask" "F.Paste")
			(net "EXP_SPARE_1")
			(options
				(clearance outline)
				(anchor circle)
			)
			(primitives
				(gr_poly
					(pts
						(arc
							(start -0.1778 -0.2794)
							(mid -0.249642 -0.249642)
							(end -0.2794 -0.1778)
						)
						(arc
							(start -0.2794 0.1778)
							(mid -0.249642 0.249642)
							(end -0.1778 0.2794)
						)
						(arc
							(start 0.1778 0.2794)
							(mid 0.249642 0.249642)
							(end 0.2794 0.1778)
						)
						(arc
							(start 0.2794 -0.1778)
							(mid 0.249642 -0.249642)
							(end 0.1778 -0.2794)
						)
					)
					(width 0)
					(fill yes)
				)
			)
		)
		(pad "2" smd custom
			(at 0 0.4445 270)
			(size 0.1397 0.1397)
			(layers "F.Cu" "F.Mask" "F.Paste")
			(net "EXP_SPARE_1_R")
			(options
				(clearance outline)
				(anchor circle)
			)
			(primitives
				(gr_poly
					(pts
						(arc
							(start -0.1778 -0.2794)
							(mid -0.249642 -0.249642)
							(end -0.2794 -0.1778)
						)
						(arc
							(start -0.2794 0.1778)
							(mid -0.249642 0.249642)
							(end -0.1778 0.2794)
						)
						(arc
							(start 0.1778 0.2794)
							(mid 0.249642 0.249642)
							(end 0.2794 0.1778)
						)
						(arc
							(start 0.2794 -0.1778)
							(mid 0.249642 -0.249642)
							(end 0.1778 -0.2794)
						)
					)
					(width 0)
					(fill yes)
				)
			)
		)
	)
)
